# BASEBOARD_FAB2 (Tioga Pass) — schematic netlist excerpt (pin names and nets, part order shuffled) for the footprints in the layout excerpt that follows; sources: Cadence DE-HDL packaged netlist, KiCad conversion of Wiwynn_Tioga_Pass_MB.brd

R9F33  RES  0.0 5% CHIP  pkg 0402  page 145 : A = PECI_BMC ; B = PECI_BMC_R
R1C9  RES  0.0 5% EMPTY  pkg 0402  page 182 : A = IRQ_BOARD_BMC_ALERT_N ; B = FAN_TACH2_R
C6B16  CAP  0.22UF 16V 10% X7R  pkg 0402  page 105 : A = P3E_CPU0_PE1_PCH_TXP<10> ; B = P3E_CPU0_PE1_PCH_C_TXP<10>

(kicad_pcb
	(version 20260206)
	(generator "pcbnew")
	(generator_version "10.0")
	(general
		(thickness 1.6)
		(legacy_teardrops no)
	)
	(paper "A4")
	(title_block
		(title "Wiwynn_Tioga_Pass_MB.brd")
		(comment 1 "Tioga Pass / footprints 640-642 of 4770")
	)
	(layers
		(0 "F.Cu" signal "TOP")
		(4 "In1.Cu" signal "L2GND")
		(6 "In2.Cu" signal "L3")
		(8 "In3.Cu" signal "L4GND")
		(10 "In4.Cu" signal "L5")
		(12 "In5.Cu" signal "L6GND")
		(14 "In6.Cu" signal "L7VCC")
		(16 "In7.Cu" signal "L8VCC")
		(18 "In8.Cu" signal "L9GND")
		(20 "In9.Cu" signal "L10")
		(22 "In10.Cu" signal "L11GND")
		(24 "In11.Cu" signal "L12")
		(26 "In12.Cu" signal "L13GND")
		(2 "B.Cu" signal "BOTTOM")
		(9 "F.Adhes" user "F.Adhesive")
		(11 "B.Adhes" user "B.Adhesive")
		(13 "F.Paste" user "Package Geometry/Pastemask Top")
		(15 "B.Paste" user "Package Geometry/Pastemask Bottom")
		(5 "F.SilkS" user "Ref Des/Silkscreen Top")
		(7 "B.SilkS" user "Ref Des/Silkscreen Bottom")
		(1 "F.Mask" user "Board Geometry/Soldermask Top")
		(3 "B.Mask" user "Board Geometry/Soldermask Bottom")
		(17 "Dwgs.User" user "User.Drawings")
		(19 "Cmts.User" user "User.Comments")
		(21 "Eco1.User" user "User.Eco1")
		(23 "Eco2.User" user "User.Eco2")
		(25 "Edge.Cuts" user "Board Geometry/Outline")
		(27 "Margin" user)
		(31 "F.CrtYd" user "Package Geometry/Place Bound Top")
		(29 "B.CrtYd" user "Package Geometry/Place Bound Bottom")
		(35 "F.Fab" user "Ref Des/Assembly Top")
		(33 "B.Fab" user "Ref Des/Assembly Bottom")
	)
	(footprint ""
		(layer "F.Cu")
		(at 337.429602 -120.038368 90)
		(property "Reference" "C6B16"
			(at -0.8382 -0.67818 90)
			(unlocked yes)
			(layer "F.SilkS")
			(effects
				(font
					(size 0.4064 0.254)
					(thickness 0.1524)
				)
				(justify left)
			)
		)
		(property "Value" ""
			(at 0 0 90)
			(layer "F.Fab")
			(effects
				(font
					(size 1.27 1.27)
				)
			)
		)
		(duplicate_pad_numbers_are_jumpers no)
		(fp_poly
			(pts
				(xy 0.3048 -0.1016) (xy 0.3048 0.9906) (xy -0.3048 0.9906) (xy -0.3048 -0.1016)
			)
			(stroke
				(width 0)
				(type default)
			)
			(fill no)
			(layer "F.CrtYd")
		)
		(fp_line
			(start 0.3048 -0.1016)
			(end -0.3048 -0.1016)
			(stroke
				(width 0.1)
				(type default)
			)
			(layer "F.Fab")
		)
		(fp_line
			(start -0.3048 -0.1016)
			(end -0.3048 0.9906)
			(stroke
				(width 0.1)
				(type default)
			)
			(layer "F.Fab")
		)
		(fp_line
			(start 0.3048 0.9906)
			(end 0.3048 -0.1016)
			(stroke
				(width 0.1)
				(type default)
			)
			(layer "F.Fab")
		)
		(fp_line
			(start -0.3048 0.9906)
			(end 0.3048 0.9906)
			(stroke
				(width 0.1)
				(type default)
			)
			(layer "F.Fab")
		)
		(pad "1" smd rect
			(at 0 0 90)
			(size 0.508 0.508)
			(layers "F.Cu" "F.Mask" "F.Paste")
			(net "P3E_CPU0_PE1_PCH_TXP<10>")
		)
		(pad "2" smd rect
			(at 0 0.889 90)
			(size 0.508 0.508)
			(layers "F.Cu" "F.Mask" "F.Paste")
			(net "P3E_CPU0_PE1_PCH_C_TXP<10>")
		)
		(zone
			(layer "F.Cu")
			(hatch none 0.5)
			(connect_pads
				(clearance 0)
			)
			(min_thickness 0.25)
			(keepout
				(tracks allowed)
				(vias not_allowed)
				(pads allowed)
				(copperpour not_allowed)
				(footprints allowed)
			)
			(placement
				(enabled no)
				(sheetname "")
			)
			(fill
				(thermal_gap 0.5)
				(thermal_bridge_width 0.5)
				(island_removal_mode 0)
			)
			(polygon
				(pts
					(xy 337.683602 -119.784368) (xy 337.683602 -120.292368) (xy 338.064602 -120.292368) (xy 338.064602 -119.784368)
				)
			)
		)
		(zone
			(layer "F.Cu")
			(hatch none 0.5)
			(connect_pads
				(clearance 0)
			)
			(min_thickness 0.25)
			(keepout
				(tracks not_allowed)
				(vias allowed)
				(pads allowed)
				(copperpour not_allowed)
				(footprints allowed)
			)
			(placement
				(enabled no)
				(sheetname "")
			)
			(fill
				(thermal_gap 0.5)
				(thermal_bridge_width 0.5)
				(island_removal_mode 0)
			)
			(polygon
				(pts
					(xy 338.064602 -119.784368) (xy 338.064602 -120.292368) (xy 337.683602 -120.292368) (xy 337.683602 -119.784368)
				)
			)
		)
	)
	(footprint ""
		(layer "F.Cu")
		(at 13.335 -101.981)
		(property "Reference" "R1C9"
			(at 0 0 0)
			(layer "F.SilkS")
			(hide yes)
			(effects
				(font
					(size 1.27 1.27)
				)
			)
		)
		(property "Value" ""
			(at 0 0 0)
			(layer "F.Fab")
			(effects
				(font
					(size 1.27 1.27)
				)
			)
		)
		(duplicate_pad_numbers_are_jumpers no)
		(fp_poly
			(pts
				(xy -0.2794 -0.1016) (xy 0.2794 -0.1016) (xy 0.2794 0.9906) (xy -0.2794 0.9906)
			)
			(stroke
				(width 0)
				(type default)
			)
			(fill no)
			(layer "F.CrtYd")
		)
		(fp_line
			(start -0.2794 -0.1016)
			(end -0.2794 0.9906)
			(stroke
				(width 0.1)
				(type default)
			)
			(layer "F.Fab")
		)
		(fp_line
			(start -0.2794 0.9906)
			(end 0.2794 0.9906)
			(stroke
				(width 0.1)
				(type default)
			)
			(layer "F.Fab")
		)
		(fp_line
			(start 0.2794 -0.1016)
			(end -0.2794 -0.1016)
			(stroke
				(width 0.1)
				(type default)
			)
			(layer "F.Fab")
		)
		(fp_line
			(start 0.2794 0.9906)
			(end 0.2794 -0.1016)
			(stroke
				(width 0.1)
				(type default)
			)
			(layer "F.Fab")
		)
		(pad "1" smd rect
			(at 0 0)
			(size 0.508 0.508)
			(layers "F.Cu" "F.Mask" "F.Paste")
			(net "IRQ_BOARD_BMC_ALERT_N")
		)
		(pad "2" smd rect
			(at 0 0.889)
			(size 0.508 0.508)
			(layers "F.Cu" "F.Mask" "F.Paste")
			(net "FAN_TACH2_R")
		)
		(zone
			(layer "F.Cu")
			(hatch none 0.5)
			(connect_pads
				(clearance 0)
			)
			(min_thickness 0.25)
			(keepout
				(tracks allowed)
				(vias not_allowed)
				(pads allowed)
				(copperpour not_allowed)
				(footprints allowed)
			)
			(placement
				(enabled no)
				(sheetname "")
			)
			(fill
				(thermal_gap 0.5)
				(thermal_bridge_width 0.5)
				(island_removal_mode 0)
			)
			(polygon
				(pts
					(xy 13.081 -101.727) (xy 13.589 -101.727) (xy 13.589 -101.346) (xy 13.081 -101.346)
				)
			)
		)
		(zone
			(layer "F.Cu")
			(hatch none 0.5)
			(connect_pads
				(clearance 0)
			)
			(min_thickness 0.25)
			(keepout
				(tracks not_allowed)
				(vias allowed)
				(pads allowed)
				(copperpour not_allowed)
				(footprints allowed)
			)
			(placement
				(enabled no)
				(sheetname "")
			)
			(fill
				(thermal_gap 0.5)
				(thermal_bridge_width 0.5)
				(island_removal_mode 0)
			)
			(polygon
				(pts
					(xy 13.081 -101.346) (xy 13.589 -101.346) (xy 13.589 -101.727) (xy 13.081 -101.727)
				)
			)
		)
	)
	(footprint ""
		(layer "F.Cu")
		(at 434.37048 -43.844464 -90)
		(property "Reference" "R9F33"
			(at 0 0 270)
			(layer "F.SilkS")
			(hide yes)
			(effects
				(font
					(size 1.27 1.27)
				)
			)
		)
		(property "Value" ""
			(at 0 0 270)
			(layer "F.Fab")
			(effects
				(font
					(size 1.27 1.27)
				)
			)
		)
		(duplicate_pad_numbers_are_jumpers no)
		(fp_poly
			(pts
				(xy -0.2794 -0.1016) (xy 0.2794 -0.1016) (xy 0.2794 0.9906) (xy -0.2794 0.9906)
			)
			(stroke
				(width 0)
				(type default)
			)
			(fill no)
			(layer "F.CrtYd")
		)
		(fp_line
			(start -0.2794 0.9906)
			(end 0.2794 0.9906)
			(stroke
				(width 0.1)
				(type default)
			)
			(layer "F.Fab")
		)
		(fp_line
			(start 0.2794 0.9906)
			(end 0.2794 -0.1016)
			(stroke
				(width 0.1)
				(type default)
			)
			(layer "F.Fab")
		)
		(fp_line
			(start -0.2794 -0.1016)
			(end -0.2794 0.9906)
			(stroke
				(width 0.1)
				(type default)
			)
			(layer "F.Fab")
		)
		(fp_line
			(start 0.2794 -0.1016)
			(end -0.2794 -0.1016)
			(stroke
				(width 0.1)
				(type default)
			)
			(layer "F.Fab")
		)
		(pad "1" smd rect
			(at 0 0 270)
			(size 0.508 0.508)
			(layers "F.Cu" "F.Mask" "F.Paste")
			(net "PECI_BMC")
		)
		(pad "2" smd rect
			(at 0 0.889 270)
			(size 0.508 0.508)
			(layers "F.Cu" "F.Mask" "F.Paste")
			(net "PECI_BMC_R")
		)
		(zone
			(layer "F.Cu")
			(hatch none 0.5)
			(connect_pads
				(clearance 0)
			)
			(min_thickness 0.25)
			(keepout
				(tracks not_allowed)
				(vias allowed)
				(pads allowed)
				(copperpour not_allowed)
				(footprints allowed)
			)
			(placement
				(enabled no)
				(sheetname "")
			)
			(fill
				(thermal_gap 0.5)
				(thermal_bridge_width 0.5)
				(island_removal_mode 0)
			)
			(polygon
				(pts
					(xy 433.73548 -44.098464) (xy 433.73548 -43.590464) (xy 434.11648 -43.590464) (xy 434.11648 -44.098464)
				)
			)
		)
		(zone
			(layer "F.Cu")
			(hatch none 0.5)
			(connect_pads
				(clearance 0)
			)
			(min_thickness 0.25)
			(keepout
				(tracks allowed)
				(vias not_allowed)
				(pads allowed)
				(copperpour not_allowed)
				(footprints allowed)
			)
			(placement
				(enabled no)
				(sheetname "")
			)
			(fill
				(thermal_gap 0.5)
				(thermal_bridge_width 0.5)
				(island_removal_mode 0)
			)
			(polygon
				(pts
					(xy 434.11648 -44.098464) (xy 434.11648 -43.590464) (xy 433.73548 -43.590464) (xy 433.73548 -44.098464)
				)
			)
		)
	)
)
